(kicad_pcb
	(version 20260206)
	(generator "pcbnew")
	(generator_version "10.0")
	(general
		(thickness 1.21888)
		(legacy_teardrops no)
	)
	(paper "A4")
	(title_block
		(title "timecard-v9 — TimeCard-DC-V9_EXP.PcbDoc")
		(comment 1 "Time Appliance Project (Time Card) / footprints 42-48 of 402")
	)
	(layers
		(0 "F.Cu" signal "TOP")
		(4 "In1.Cu" signal "SGND")
		(6 "In2.Cu" signal "IN1")
		(8 "In3.Cu" signal "IN2")
		(10 "In4.Cu" signal "SGND1")
		(2 "B.Cu" signal "BOTTOM")
		(9 "F.Adhes" user "F.Adhesive")
		(11 "B.Adhes" user "B.Adhesive")
		(13 "F.Paste" user "Top Paste")
		(15 "B.Paste" user "Bottom Paste")
		(5 "F.SilkS" user "Top Overlay")
		(7 "B.SilkS" user "Bottom Overlay")
		(1 "F.Mask" user "Top Solder")
		(3 "B.Mask" user "Bottom Solder")
		(17 "Dwgs.User" user "User.Drawings")
		(19 "Cmts.User" user "User.Comments")
		(21 "Eco1.User" user "User.Eco1")
		(23 "Eco2.User" user "User.Eco2")
		(25 "Edge.Cuts" user)
		(27 "Margin" user)
		(31 "F.CrtYd" user "Top Courtyard")
		(29 "B.CrtYd" user "Bottom Courtyard")
		(35 "F.Fab" user "Top Component Center")
		(33 "B.Fab" user "Bottom Component Center")
	)
	(footprint "Vault:AMPH-901-143-6RFX_V"
		(layer "F.Cu")
		(at 69.9716 135.5786 180)
		(property "Reference" "AN4"
			(at 0.95 3.669055 0)
			(unlocked yes)
			(layer "F.SilkS")
			(effects
				(font
					(size 0.762 0.762)
					(thickness 0.2286)
				)
				(justify left bottom)
			)
		)
		(property "Value" "RF2-49B-T-00-50-G-HDW"
			(at 4.6101 -12.120245 0)
			(unlocked yes)
			(layer "F.SilkS")
			(hide yes)
			(effects
				(font
					(size 0.762 0.762)
					(thickness 0.2286)
				)
				(justify left bottom)
			)
		)
		(sheetname "01-USER_IO")
		(sheetfile "01-USER_IO.kicad_sch")
		(duplicate_pad_numbers_are_jumpers no)
		(fp_line
			(start 3.5 -1.38)
			(end 3.5 1.38)
			(stroke
				(width 0.2)
				(type solid)
			)
			(layer "F.SilkS")
		)
		(fp_line
			(start 1.38 3.5)
			(end -1.38 3.5)
			(stroke
				(width 0.2)
				(type solid)
			)
			(layer "F.SilkS")
		)
		(fp_line
			(start 1.38 -3.5)
			(end -1.38 -3.5)
			(stroke
				(width 0.2)
				(type solid)
			)
			(layer "F.SilkS")
		)
		(fp_line
			(start -3.5 -1.38)
			(end -3.5 1.38)
			(stroke
				(width 0.2)
				(type solid)
			)
			(layer "F.SilkS")
		)
		(pad "1" thru_hole rect
			(at 0 0 180)
			(size 2 2)
			(drill 1.5)
			(layers "*.Cu" "*.Mask")
			(remove_unused_layers no)
			(net "NetAN4_1")
		)
		(pad "2" thru_hole circle
			(at -2.54 -2.54 180)
			(size 2.2 2.2)
			(drill 1.7)
			(layers "*.Cu" "*.Mask")
			(remove_unused_layers no)
			(net "GND")
			(thermal_bridge_angle 90)
		)
		(pad "3" thru_hole circle
			(at -2.54 2.54 180)
			(size 2.2 2.2)
			(drill 1.7)
			(layers "*.Cu" "*.Mask")
			(remove_unused_layers no)
			(net "GND")
			(thermal_bridge_angle 90)
		)
		(pad "4" thru_hole circle
			(at 2.54 2.54 180)
			(size 2.2 2.2)
			(drill 1.7)
			(layers "*.Cu" "*.Mask")
			(remove_unused_layers no)
			(net "GND")
			(thermal_bridge_angle 90)
		)
		(pad "5" thru_hole circle
			(at 2.54 -2.54 180)
			(size 2.2 2.2)
			(drill 1.7)
			(layers "*.Cu" "*.Mask")
			(remove_unused_layers no)
			(net "GND")
			(thermal_bridge_angle 90)
		)
	)
	(footprint "Vault:FP-RUT0012A-MFG"
		(layer "F.Cu")
		(at 158.3216 129.5162)
		(property "Reference" "U21"
			(at 0.678605 -2.159259 0)
			(unlocked yes)
			(layer "F.SilkS")
			(effects
				(font
					(size 0.762 0.762)
					(thickness 0.2286)
				)
			)
		)
		(property "Value" "TMUX1072RUTR"
			(at 7.426665 3.164071 0)
			(unlocked yes)
			(layer "F.SilkS")
			(hide yes)
			(effects
				(font
					(size 0.762 0.762)
					(thickness 0.2286)
				)
			)
		)
		(sheetname "09-USBUart_PPSMUX_UARTMUX")
		(sheetfile "09-USBUart_PPSMUX_UARTMUX.kicad_sch")
		(duplicate_pad_numbers_are_jumpers no)
		(fp_line
			(start -0.9 -1.525)
			(end 0.9 -1.525)
			(stroke
				(width 0.2)
				(type solid)
			)
			(layer "F.SilkS")
		)
		(fp_line
			(start -0.9 1.525)
			(end 0.9 1.525)
			(stroke
				(width 0.2)
				(type solid)
			)
			(layer "F.SilkS")
		)
		(fp_circle
			(center -1.575 -0.8)
			(end -1.575 -0.925)
			(stroke
				(width 0.25)
				(type solid)
			)
			(fill no)
			(layer "F.SilkS")
		)
		(fp_rect
			(start -0.85 -0.3)
			(end -0.35 -0.5)
			(stroke
				(width 0)
				(type default)
			)
			(fill yes)
			(layer "F.Paste")
		)
		(fp_rect
			(start -0.85 0.1)
			(end -0.35 -0.1)
			(stroke
				(width 0)
				(type default)
			)
			(fill yes)
			(layer "F.Paste")
		)
		(fp_rect
			(start -0.85 0.5)
			(end -0.35 0.3)
			(stroke
				(width 0)
				(type default)
			)
			(fill yes)
			(layer "F.Paste")
		)
		(fp_rect
			(start -0.85 0.9)
			(end -0.35 0.7)
			(stroke
				(width 0)
				(type default)
			)
			(fill yes)
			(layer "F.Paste")
		)
		(fp_rect
			(start -0.1 -0.5)
			(end 0.1 -1)
			(stroke
				(width 0)
				(type default)
			)
			(fill yes)
			(layer "F.Paste")
		)
		(fp_rect
			(start -0.1 1)
			(end 0.1 0.5)
			(stroke
				(width 0)
				(type default)
			)
			(fill yes)
			(layer "F.Paste")
		)
		(fp_rect
			(start 0.35 -0.7)
			(end 0.85 -0.9)
			(stroke
				(width 0)
				(type default)
			)
			(fill yes)
			(layer "F.Paste")
		)
		(fp_rect
			(start 0.35 -0.3)
			(end 0.85 -0.5)
			(stroke
				(width 0)
				(type default)
			)
			(fill yes)
			(layer "F.Paste")
		)
		(fp_rect
			(start 0.35 0.1)
			(end 0.85 -0.1)
			(stroke
				(width 0)
				(type default)
			)
			(fill yes)
			(layer "F.Paste")
		)
		(fp_rect
			(start 0.35 0.5)
			(end 0.85 0.3)
			(stroke
				(width 0)
				(type default)
			)
			(fill yes)
			(layer "F.Paste")
		)
		(fp_rect
			(start 0.35 0.9)
			(end 0.85 0.7)
			(stroke
				(width 0)
				(type default)
			)
			(fill yes)
			(layer "F.Paste")
		)
		(fp_poly
			(pts
				(xy -0.5 -1) (xy -0.35 -1) (xy -0.35 -0.7) (xy -0.85 -0.7) (xy -0.85 -0.9) (xy -0.5 -0.9)
			)
			(stroke
				(width 0)
				(type default)
			)
			(fill yes)
			(layer "F.Paste")
		)
		(fp_line
			(start -1.05 -1.2)
			(end 1.05 -1.2)
			(stroke
				(width 0.2)
				(type solid)
			)
			(layer "F.CrtYd")
		)
		(fp_line
			(start -1.05 1.2)
			(end -1.05 -1.2)
			(stroke
				(width 0.2)
				(type solid)
			)
			(layer "F.CrtYd")
		)
		(fp_line
			(start -1.05 1.2)
			(end 1.05 1.2)
			(stroke
				(width 0.2)
				(type solid)
			)
			(layer "F.CrtYd")
		)
		(fp_line
			(start 1.05 1.2)
			(end 1.05 -1.2)
			(stroke
				(width 0.2)
				(type solid)
			)
			(layer "F.CrtYd")
		)
		(fp_line
			(start -1.05 -1.2)
			(end 1.05 -1.2)
			(stroke
				(width 0.2)
				(type solid)
			)
			(layer "F.Fab")
		)
		(fp_line
			(start -1.05 1.2)
			(end -1.05 -1.2)
			(stroke
				(width 0.2)
				(type solid)
			)
			(layer "F.Fab")
		)
		(fp_line
			(start -1.05 1.2)
			(end 1.05 1.2)
			(stroke
				(width 0.2)
				(type solid)
			)
			(layer "F.Fab")
		)
		(fp_line
			(start -0.5 0)
			(end 0.5 0)
			(stroke
				(width 0.1)
				(type solid)
			)
			(layer "F.Fab")
		)
		(fp_line
			(start 0 0.5)
			(end 0 -0.5)
			(stroke
				(width 0.1)
				(type solid)
			)
			(layer "F.Fab")
		)
		(fp_line
			(start 1.05 1.2)
			(end 1.05 -1.2)
			(stroke
				(width 0.2)
				(type solid)
			)
			(layer "F.Fab")
		)
		(fp_text user "${REFERENCE}"
			(at -0.00001 0.09602 0)
			(unlocked yes)
			(layer "F.Fab")
			(effects
				(font
					(face "Arial")
					(size 0.63 0.63)
					(thickness 0.1)
				)
				(justify left bottom)
			)
		)
		(pad "" smd custom
			(at -0.5 -1.1)
			(size 0.000001 0.000001)
			(layers "F.Cu" "F.Mask")
			(solder_mask_margin 0)
			(thermal_bridge_angle 90)
			(options
				(clearance outline)
				(anchor circle)
			)
			(primitives
				(gr_poly
					(pts
						(xy 0 0) (xy 0.15 0) (xy 0.15 0.4) (xy -0.45 0.4) (xy -0.45 0.2) (xy 0 0.2)
					)
					(width 0)
					(fill yes)
				)
			)
		)
		(pad "1" smd circle
			(at -0.45 -0.8)
			(size 0.18 0.18)
			(layers "F.Cu" "F.Mask" "F.Paste")
			(net "DIP_SW_UART_SEL")
			(solder_mask_margin 0)
			(solder_paste_margin -1000)
			(thermal_bridge_angle 90)
		)
		(pad "2" smd rect
			(at -0.65 -0.4)
			(size 0.6 0.2)
			(layers "F.Cu" "F.Mask" "F.Paste")
			(net "NetR85_2")
			(solder_mask_margin 0)
			(solder_paste_margin -1000)
		)
		(pad "3" smd rect
			(at -0.65 0)
			(size 0.6 0.2)
			(layers "F.Cu" "F.Mask" "F.Paste")
			(net "GND")
			(solder_mask_margin 0)
			(solder_paste_margin -1000)
		)
		(pad "4" smd rect
			(at -0.65 0.4)
			(size 0.6 0.2)
			(layers "F.Cu" "F.Mask" "F.Paste")
			(net "NetR87_2")
			(solder_mask_margin 0)
			(solder_paste_margin -1000)
		)
		(pad "5" smd rect
			(at -0.65 0.8)
			(size 0.6 0.2)
			(layers "F.Cu" "F.Mask" "F.Paste")
			(net "DIP_SW_UART_SEL")
			(solder_mask_margin 0)
			(solder_paste_margin -1000)
		)
		(pad "6" smd rect
			(at 0 0.8)
			(size 0.2 0.6)
			(layers "F.Cu" "F.Mask" "F.Paste")
			(net "GND")
			(solder_mask_margin 0)
			(solder_paste_margin -1000)
		)
		(pad "7" smd rect
			(at 0.65 0.8)
			(size 0.6 0.2)
			(layers "F.Cu" "F.Mask" "F.Paste")
			(net "UART1_RXD")
			(solder_mask_margin 0)
			(solder_paste_margin -1000)
		)
		(pad "8" smd rect
			(at 0.65 0.4)
			(size 0.6 0.2)
			(layers "F.Cu" "F.Mask" "F.Paste")
			(net "NetR86_2")
			(solder_mask_margin 0)
			(solder_paste_margin -1000)
		)
		(pad "9" smd rect
			(at 0.65 0)
			(size 0.6 0.2)
			(layers "F.Cu" "F.Mask" "F.Paste")
			(net "+3.3V")
			(solder_mask_margin 0)
			(solder_paste_margin -1000)
		)
		(pad "10" smd rect
			(at 0.65 -0.4)
			(size 0.6 0.2)
			(layers "F.Cu" "F.Mask" "F.Paste")
			(net "NetR84_2")
			(solder_mask_margin 0)
			(solder_paste_margin -1000)
		)
		(pad "11" smd rect
			(at 0.65 -0.8)
			(size 0.6 0.2)
			(layers "F.Cu" "F.Mask" "F.Paste")
			(net "UART1_TXD")
			(solder_mask_margin 0)
			(solder_paste_margin -1000)
		)
		(pad "12" smd rect
			(at 0 -0.8)
			(size 0.2 0.6)
			(layers "F.Cu" "F.Mask" "F.Paste")
			(net "GND")
			(solder_mask_margin 0)
			(solder_paste_margin -1000)
		)
	)
	(footprint "Vault:RESC1005X40X25NL05T05"
		(layer "F.Cu")
		(at 154.0216 113.2162)
		(property "Reference" "R74"
			(at -2.1714 0.126931 0)
			(unlocked yes)
			(layer "F.SilkS")
			(effects
				(font
					(size 0.762 0.762)
					(thickness 0.2286)
				)
			)
		)
		(property "Value" "DNI_27_1%_0402"
			(at -2.884671 8.544305 270)
			(unlocked yes)
			(layer "F.SilkS")
			(hide yes)
			(effects
				(font
					(size 0.762 0.762)
					(thickness 0.2286)
				)
			)
		)
		(sheetname "08-DIPSwitches_I2C")
		(sheetfile "08-DIPSwitches_I2C.kicad_sch")
		(duplicate_pad_numbers_are_jumpers no)
		(pad "1" smd rect
			(at -0.45 0 90)
			(size 0.55 0.55)
			(layers "F.Cu" "F.Mask" "F.Paste")
			(net "FPGA_MAC_UART_TX")
		)
		(pad "2" smd rect
			(at 0.45 0 90)
			(size 0.55 0.55)
			(layers "F.Cu" "F.Mask" "F.Paste")
			(net "MAC_TX")
		)
	)
	(footprint "Vault:CAPC1608X87X45ML20T05"
		(layer "F.Cu")
		(at 105.45022 83.17365)
		(property "Reference" "C31"
			(at 2.651465 -0.026931 180)
			(unlocked yes)
			(layer "F.SilkS")
			(effects
				(font
					(size 0.762 0.762)
					(thickness 0.2286)
				)
			)
		)
		(property "Value" "0.1uF"
			(at 2.069025 2.630671 0)
			(unlocked yes)
			(layer "F.SilkS")
			(hide yes)
			(effects
				(font
					(size 0.762 0.762)
					(thickness 0.2286)
				)
			)
		)
		(sheetname "05-GPS_IMU_SENSORS")
		(sheetfile "05-GPS_IMU_SENSORS.kicad_sch")
		(duplicate_pad_numbers_are_jumpers no)
		(pad "1" smd rect
			(at -0.7 0 90)
			(size 1.1 1.05)
			(layers "F.Cu" "F.Mask" "F.Paste")
			(net "GND")
		)
		(pad "2" smd rect
			(at 0.7 0 90)
			(size 1.1 1.05)
			(layers "F.Cu" "F.Mask" "F.Paste")
			(net "+3.3V")
		)
	)
	(footprint "GNSS:GNSS Header 16-pin"
		(locked yes)
		(layer "F.Cu")
		(at 215.0592 140.4387 90)
		(property "Reference" "J13"
			(at 5.1939 1.735469 270)
			(unlocked yes)
			(layer "F.SilkS")
			(effects
				(font
					(size 0.762 0.762)
					(thickness 0.2286)
				)
			)
		)
		(property "Value" "GNSS Header 16-pin"
			(at 6.740165 4.840511 90)
			(unlocked yes)
			(layer "F.SilkS")
			(hide yes)
			(effects
				(font
					(size 0.762 0.762)
					(thickness 0.2286)
				)
			)
		)
		(sheetname "05-GPS_IMU_SENSORS")
		(sheetfile "05-GPS_IMU_SENSORS.kicad_sch")
		(duplicate_pad_numbers_are_jumpers no)
		(fp_line
			(start 8.5 -7.5)
			(end 8.5 0.5)
			(stroke
				(width 0.0254)
				(type solid)
			)
			(layer "F.SilkS")
		)
		(fp_line
			(start -0.5 -7.5)
			(end 8.5 -7.5)
			(stroke
				(width 0.0254)
				(type solid)
			)
			(layer "F.SilkS")
		)
		(fp_line
			(start -0.5 -7.5)
			(end -0.5 0.5)
			(stroke
				(width 0.0254)
				(type solid)
			)
			(layer "F.SilkS")
		)
		(fp_line
			(start -0.5 0.5)
			(end 8.5 0.5)
			(stroke
				(width 0.0254)
				(type solid)
			)
			(layer "F.SilkS")
		)
		(fp_circle
			(center 0 -0.5)
			(end 0.0254 -0.5)
			(stroke
				(width 0.508)
				(type solid)
			)
			(fill no)
			(layer "F.SilkS")
		)
		(fp_text user "Orig 2x4"
			(at 7.664175 -6.06619 360)
			(unlocked yes)
			(layer "F.SilkS")
			(effects
				(font
					(size 0.762 0.762)
					(thickness 0.2286)
				)
				(justify left bottom)
			)
		)
		(pad "0" thru_hole circle
			(at 4 -13.49999)
			(size 0 0)
			(drill 0.76)
			(layers "*.Cu" "*.Mask")
			(remove_unused_layers no)
			(thermal_bridge_angle 90)
		)
		(pad "0" thru_hole circle
			(at 4 -1.5)
			(size 0 0)
			(drill 0.76)
			(layers "*.Cu" "*.Mask")
			(remove_unused_layers no)
			(thermal_bridge_angle 90)
		)
		(pad "1" smd rect
			(at 1.7775 -0.5)
			(size 1.12 2.105)
			(layers "F.Cu" "F.Mask" "F.Paste")
			(net "GNSS2_P5V0")
		)
		(pad "2" smd rect
			(at 6.2225 -0.5)
			(size 1.12 2.105)
			(layers "F.Cu" "F.Mask" "F.Paste")
			(net "GNSS2_P3V3")
		)
		(pad "3" smd rect
			(at 1.7775 -2.5)
			(size 1.12 2.105)
			(layers "F.Cu" "F.Mask" "F.Paste")
			(net "RCB_GPS2_TX")
		)
		(pad "4" smd rect
			(at 6.2225 -2.5)
			(size 1.12 2.105)
			(layers "F.Cu" "F.Mask" "F.Paste")
			(net "GPS2_RST")
		)
		(pad "5" smd rect
			(at 1.7775 -4.5)
			(size 1.12 2.105)
			(layers "F.Cu" "F.Mask" "F.Paste")
			(net "RCB_GPS2_RX")
		)
		(pad "6" smd rect
			(at 6.2225 -4.5)
			(size 1.12 2.105)
			(layers "F.Cu" "F.Mask" "F.Paste")
			(net "RCB_GPS2_TP1")
		)
		(pad "7" smd rect
			(at 1.7775 -6.5)
			(size 1.12 2.105)
			(layers "F.Cu" "F.Mask" "F.Paste")
			(net "RCB_GPS2_TP2")
		)
		(pad "8" smd rect
			(at 6.2225 -6.5)
			(size 1.12 2.105)
			(layers "F.Cu" "F.Mask" "F.Paste")
			(net "GND")
		)
		(pad "9" smd rect
			(at 1.7775 -8.50001)
			(size 1.12 2.105)
			(layers "F.Cu" "F.Mask" "F.Paste")
			(net "GNSS2_P5V0")
		)
		(pad "10" smd rect
			(at 6.2225 -8.50001)
			(size 1.12 2.105)
			(layers "F.Cu" "F.Mask" "F.Paste")
			(net "GNSS2_P3V3")
		)
		(pad "11" smd rect
			(at 1.7775 -10.50001)
			(size 1.12 2.105)
			(layers "F.Cu" "F.Mask" "F.Paste")
			(net "RCB_GPS2_PIN11")
		)
		(pad "12" smd rect
			(at 6.2225 -10.50001)
			(size 1.12 2.105)
			(layers "F.Cu" "F.Mask" "F.Paste")
			(net "RCB_GPS2_PIN12")
		)
		(pad "13" smd rect
			(at 1.7775 -12.50001)
			(size 1.12 2.105)
			(layers "F.Cu" "F.Mask" "F.Paste")
			(net "GPS2_PIN13")
		)
		(pad "14" smd rect
			(at 6.2225 -12.50001)
			(size 1.12 2.105)
			(layers "F.Cu" "F.Mask" "F.Paste")
			(net "GPS2_PIN14")
		)
		(pad "15" smd rect
			(at 1.7775 -14.5)
			(size 1.12 2.105)
			(layers "F.Cu" "F.Mask" "F.Paste")
			(net "GPS2_PIN15")
		)
		(pad "16" smd rect
			(at 6.2225 -14.5)
			(size 1.12 2.105)
			(layers "F.Cu" "F.Mask" "F.Paste")
			(net "GND")
		)
	)
	(footprint "Vault:FP-GRM31C-0_2-e0_3_0_8-IPC_C"
		(layer "F.Cu")
		(at 184.7216 84.9162 90)
		(property "Reference" "C76"
			(at 0.46924 -2.601729 90)
			(unlocked yes)
			(layer "F.SilkS")
			(effects
				(font
					(size 0.762 0.762)
					(thickness 0.2286)
				)
			)
		)
		(property "Value" "4.7uF_50V_1206"
			(at 8.594615 2.719551 90)
			(unlocked yes)
			(layer "F.SilkS")
			(hide yes)
			(effects
				(font
					(size 0.762 0.762)
					(thickness 0.2286)
				)
			)
		)
		(sheetname "03-POWER")
		(sheetfile "03-POWER.kicad_sch")
		(duplicate_pad_numbers_are_jumpers no)
		(fp_line
			(start -0.39846 -0.9)
			(end 0.39847 -0.9)
			(stroke
				(width 0.2)
				(type solid)
			)
			(layer "F.SilkS")
		)
		(fp_line
			(start -0.39846 0.9)
			(end 0.39847 0.9)
			(stroke
				(width 0.2)
				(type solid)
			)
			(layer "F.SilkS")
		)
		(fp_line
			(start 1.9531 -1)
			(end 1.9531 1)
			(stroke
				(width 0.2)
				(type solid)
			)
			(layer "F.CrtYd")
		)
		(fp_line
			(start -1.9531 -1)
			(end 1.9531 -1)
			(stroke
				(width 0.2)
				(type solid)
			)
			(layer "F.CrtYd")
		)
		(fp_line
			(start -1.9531 -1)
			(end -1.9531 1)
			(stroke
				(width 0.2)
				(type solid)
			)
			(layer "F.CrtYd")
		)
		(fp_line
			(start -1.9531 1)
			(end 1.9531 1)
			(stroke
				(width 0.2)
				(type solid)
			)
			(layer "F.CrtYd")
		)
		(fp_line
			(start 1.9531 -1)
			(end 1.9531 1)
			(stroke
				(width 0.2)
				(type solid)
			)
			(layer "F.Fab")
		)
		(fp_line
			(start -1.9531 -1)
			(end 1.9531 -1)
			(stroke
				(width 0.2)
				(type solid)
			)
			(layer "F.Fab")
		)
		(fp_line
			(start -1.9531 -1)
			(end -1.9531 1)
			(stroke
				(width 0.2)
				(type solid)
			)
			(layer "F.Fab")
		)
		(fp_line
			(start 0 -0.5)
			(end 0 0.5)
			(stroke
				(width 0.1)
				(type solid)
			)
			(layer "F.Fab")
		)
		(fp_line
			(start -0.5 0)
			(end 0.5 0)
			(stroke
				(width 0.1)
				(type solid)
			)
			(layer "F.Fab")
		)
		(fp_line
			(start -1.9531 1)
			(end 1.9531 1)
			(stroke
				(width 0.2)
				(type solid)
			)
			(layer "F.Fab")
		)
		(fp_text user "${REFERENCE}"
			(at -0.00001 0.09602 90)
			(unlocked yes)
			(layer "F.Fab")
			(effects
				(font
					(face "Arial")
					(size 0.63 0.63)
					(thickness 0.1)
				)
				(justify left bottom)
			)
		)
		(pad "1" smd rect
			(at -1.27578 0 90)
			(size 1.15464 1.7062)
			(layers "F.Cu" "F.Mask" "F.Paste")
			(net "+12V")
			(solder_mask_margin 0)
			(solder_paste_margin 0)
		)
		(pad "2" smd rect
			(at 1.27578 0 90)
			(size 1.15464 1.7062)
			(layers "F.Cu" "F.Mask" "F.Paste")
			(net "GND")
			(solder_mask_margin 0)
			(solder_paste_margin 0)
		)
	)
	(footprint "Vault:RESC1005X40X25NL05T05"
		(layer "F.Cu")
		(at 158.3216 126.5162)
		(property "Reference" "R100"
			(at 0.728869 -1.6714 270)
			(unlocked yes)
			(layer "F.SilkS")
			(effects
				(font
					(size 0.762 0.762)
					(thickness 0.2286)
				)
			)
		)
		(property "Value" "DNI_27_1%_0402"
			(at -2.732271 10.296375 270)
			(unlocked yes)
			(layer "F.SilkS")
			(hide yes)
			(effects
				(font
					(size 0.762 0.762)
					(thickness 0.2286)
				)
			)
		)
		(sheetname "09-USBUart_PPSMUX_UARTMUX")
		(sheetfile "09-USBUart_PPSMUX_UARTMUX.kicad_sch")
		(duplicate_pad_numbers_are_jumpers no)
		(pad "1" smd rect
			(at -0.45 0 90)
			(size 0.55 0.55)
			(layers "F.Cu" "F.Mask" "F.Paste")
			(net "FTDI_RX")
		)
		(pad "2" smd rect
			(at 0.45 0 90)
			(size 0.55 0.55)
			(layers "F.Cu" "F.Mask" "F.Paste")
			(net "UART1_TXD")
		)
	)
)
